FILE_TYPE = CONNECTIVITY;
{Allegro Design Entry HDL 17.2-2016 S081 (4005846) 1/11/2022}
"PAGE_NUMBER" = 195;
0"NC";
1"P3V3\g";
2"P3V3\g";
3"P3V3_DB2000_VDDA\g";
4"P3V3\g";
5"P3V3_DB2000_VDD\g";
6"P3V3_DB2000_VDDR\g";
7"P3V3_DB2000_VDD\g";
8"P3V3_DB2000_VDDR\g";
9"P3V3\g";
10"P3V3\g";
11"P3V3_DB2000_VDDA\g";
12"GND\g";
13"GND\g";
14"GND\g";
15"GND\g";
16"GND\g";
17"GND\g";
18"GND\g";
19"GND\g";
20"PD_DB2000_SMB_SA0";
21"OCP_SFF_CLK_OE_N";
22"CLK_SWB_OE_N";
23"P3V3_DB2000_FB_VDD";
24"FM_DB2000_OE_N";
25"FM_PLD_CLKS_DEV_EN";
26"NC_CLK_100M_DB2000_NC13";
27"FM_DB2000_VSBEN";
28"NC_CLK_100M_DB2000_NC16";
29"NC_CLK_100M_DB2000_NC14";
30"NC_CLK_100M_DB2000_NC17";
31"NC_CLK_100M_DB2000_NC5";
32"NC_CLK_100M_DB2000_NC6";
33"CLK_100M_DB2000_CPU0_BCLK1_DP";
34"CLK_100M_DB2000_CPU0_BCLK0_DP";
35"CLK_100M_DB2000_CPU0_BCLK1_DN";
36"PD_DB2000_SMB_SA1";
37"CLK_100M_DB2000_CPU0_BCLK0_DN";
38"CLK_100M_DB2000_CPU0_BCLK2_DP";
39"CLK_100M_DB2000_CPU0_BCLK3_DP";
40"CLK_100M_OCP_V3_2_C_R_DP";
41"SMB_HOST_DB2000_3V3AUX_SDA";
42"PD_DB2000_SMB_SA0";
43"NC_CLK_100M_DB2000_NC9";
44"NC_CLK_100M_DB2000_NC7";
45"NC_CLK_100M_DB2000_NC10";
46"NC_CLK_100M_DB2000_NC12";
47"NC_CLK_100M_DB2000_NC15";
48"CLK_100M_DB2000_CPU0_BCLK2_DN";
49"CLK_100M_DB2000_CPU0_BCLK3_DN";
50"CLK_100M_DB2000_DP";
51"CLK_100M_DB2000_DN";
52"CLK_100M_DB2000_CPU1_BCLK0_DP";
53"CLK_100M_DB2000_CPU1_BCLK1_DP";
54"CLK_100M_DB2000_CPU1_BCLK2_DP";
55"NC_CLK_100M_DB2000_NC18";
56"SMB_HOST_DB2000_3V3AUX_SCL";
57"CLK_100M_DB2000_CPU1_BCLK3_DP";
58"FM_DB2000_DEV_EN";
59"CLK_100M_OCP_V3_2_B_R_DN";
60"CLK_100M_OCP_V3_2_B_R_DP";
61"CLK_100M_DB2000_CPU1_BCLK1_DN";
62"CLK_100M_DB2000_CPU1_BCLK2_DN";
63"CLK_100M_GPU_SWB_REF_DP";
64"NC_CLK_100M_DB2000_NC11";
65"NC_CLK_100M_DB2000_NC8";
66"NC_CLK_100M_DB2000_NC3";
67"NC_CLK_100M_DB2000_NC4";
68"CLK_100M_OCP_V3_2_A_R_DN";
69"FM_DB2000_10_OE_N";
70"FM_DB2000_12_OE_N";
71"FM_DB2000_8_OE_N";
72"PD_DB2000_SMB_SA1";
73"FM_DB2000_VSBEN";
74"CLK_100M_DB2000_CPU1_BCLK0_DN";
75"FM_DB2000_11_OE_N";
76"TP_CLK_100M_DIF13_DN";
77"CLK_100M_OCP_V3_2_A_R_DP";
78"CLK_100M_GPU_SWB_REF_DN";
79"CLK_100M_DB2000_CPU1_BCLK3_DN";
80"FM_DB2000_1_OE_N";
81"NC_CLK_100M_DB2000_NC1";
82"NC_CLK_100M_DB2000_NC2";
83"TP_CLK_100M_DIF19_DP";
84"TP_CLK_100M_DIF19_DN";
85"TP_CLK_100M_DIF18_DN";
86"TP_CLK_100M_DIF18_DP";
87"CLK_100M_OCP_V3_2_C_R_DN";
88"CLK_100M_OCP_V3_2_D_R_DP";
89"CLK_100M_OCP_V3_2_D_R_DN";
90"FM_DB2000_9_OE_N";
91"TP_CLK_100M_DIF13_DP";
92"CLK_100M_OCP_SFF_3_R_DN";
93"CLK_100M_OCP_SFF_3_R_DP";
94"CLK_100M_OCP_SFF_2_R_DN";
95"CLK_100M_OCP_SFF_2_R_DP";
96"CLK_100M_OCP_SFF_1_R_DN";
97"CLK_100M_OCP_SFF_1_R_DP";
98"CLK_100M_OCP_SFF_0_R_DN";
99"CLK_100M_OCP_SFF_0_R_DP";
%"9QXL2001BNHGI8"
"1","(-3200,2275)","0","pure_quanta","I119";
;
PART_NUMBER"AJ020010003"
PART_TYPE"SMLF"
MATERIAL"IC"
VALUE"9QXL2001BNHGI8"
$LOCATION"U38"
CDS_LMAN_SYM_OUTLINE"-425,1875,425,-1875"
NEEDS_NO_SIZE"TRUE"
CDS_LIB"pure_quanta"
CDS_LOCATION"U38"
$SEC"1"
CDS_SEC"1";
"DIF19# \B"
$PN"F1"84;
"DIF19"
$PN"E1"83;
"^VSADR1_TRI"
$PN"B8"36;
"^VSADR0_TRI"
$PN"B4"42;
"VDDR3.3"
$PN"H2"8;
"VDDO3.3_L11"
$PN"L11"5;
"VDDO3.3_L2"
$PN"L2"5;
"VDDO3.3_B11"
$PN"B11"5;
"VDDO3.3_B2"
$PN"B2"5;
"VDDA3.3"
$PN"B6"11;
"SMBDAT"
$PN"L4"41;
"SMBCLK"
$PN"L5"56;
"VOE12# \B"
$PN"B10"70;
"VOE11# \B"
$PN"C11"75;
"VOE10#||SHFT_LD# \B"
$PN"E11"69;
"VOE9# \B"
$PN"E12"90;
"VOE8# \B"
$PN"H11"71;
"VOE7# \B"
$PN"K11"80;
"VOE6#||CLK \B"
$PN"L10"80;
"VOE5#||DATA \B"
$PN"L8"80;
"VSBEN"
$PN"E2"73;
"DIF9# \B"
$PN"F12"98;
"DIF9"
$PN"G12"99;
"DIF8# \B"
$PN"H12"78;
"DIF8"
$PN"J12"63;
"DIF7# \B"
$PN"K12"79;
"DIF7"
$PN"L12"57;
"DIF6# \B"
$PN"M12"62;
"DIF6"
$PN"M11"54;
"DIF5# \B"
$PN"M10"61;
"DIF5"
$PN"M9"53;
"DIF4# \B"
$PN"M8"74;
"DIF4"
$PN"M7"52;
"DIF3# \B"
$PN"M5"49;
"DIF3"
$PN"M4"39;
"DIF2# \B"
$PN"M3"48;
"DIF2"
$PN"M2"38;
"NC6"
$PN"D2"32;
"NC5"
$PN"C2"31;
"NC4"
$PN"B9"67;
"NC3"
$PN"B7"66;
"NC2"
$PN"B5"82;
"NC18"
$PN"L9"55;
"NC17"
$PN"L3"30;
"NC16"
$PN"L7"28;
"NC7"
$PN"D11"44;
"NC9"
$PN"F11"43;
"DIF17# \B"
$PN"B1"89;
"DIF13"
$PN"A9"91;
"DIF11# \B"
$PN"A12"94;
"DIF_IN"
$PN"G1"50;
"DIF18"
$PN"C1"86;
"DIF16# \B"
$PN"A2"87;
"DIF16"
$PN"A3"40;
"DIF15# \B"
$PN"A4"59;
"DIF14# \B"
$PN"A6"68;
"DIF14"
$PN"A7"77;
"DIF13# \B"
$PN"A8"76;
"DIF12"
$PN"A11"93;
"DIF12# \B"
$PN"A10"92;
"DIF11"
$PN"B12"95;
"DIF10# \B"
$PN"C12"96;
"DIF10"
$PN"D12"97;
"DIF1# \B"
$PN"M1"35;
"DIF1"
$PN"L1"33;
"DIF0# \B"
$PN"K1"37;
"DIF0"
$PN"J1"34;
"NC13"
$PN"J11"26;
"NC15"
$PN"L6"47;
"NC14"
$PN"K2"29;
"NC11"
$PN"G11"64;
"NC8"
$PN"F2"65;
"EPAD"
$PN"TH"12;
"VCKPWRGD_PD# \B"
$PN"M6"58;
"DIF18# \B"
$PN"D1"85;
"DIF17"
$PN"A1"88;
"DIF15"
$PN"A5"60;
"NC10"
$PN"G2"45;
"NC1"
$PN"B3"81;
"NC12"
$PN"J2"46;
"DIF_IN# \B"
$PN"H1"51;
%"Q_RES"
"1","(-5300,2250)","0","pure_quanta","I156";
;
PART_NUMBER"CS04992FB07"
WATTAGE"1/16W"
VALUE"49.9"
PACK_TYPE"0402LF"
TOLERANCE"1%"
MATERIAL"CHIP"
$LOCATION"R576"
CDS_LIB"pure_quanta"
CDS_LOCATION"R576"
$SEC"1"
CDS_SEC"1";
"B"
$PN"2"80;
"A"
$PN"1"24;
%"UNIVERSAL_POWER"
"1","(-4125,4250)","0","logical_power","I158";
;
HDL_POWER"P3V3_DB2000_VDD"
CDS_LIB"logical_power";
"A"5;
%"UNIVERSAL_POWER"
"1","(-4575,4350)","0","logical_power","I159";
;
HDL_POWER"P3V3_DB2000_VDDA"
CDS_LIB"logical_power";
"A"11;
%"UNIVERSAL_POWER"
"1","(-5025,4450)","0","logical_power","I160";
;
HDL_POWER"P3V3_DB2000_VDDR"
CDS_LIB"logical_power";
"A"8;
%"UNIVERSAL_POWER"
"1","(-9425,4500)","0","logical_power","I161";
;
HDL_POWER"P3V3"
CDS_LIB"logical_power";
"A"2;
%"Q_RES"
"1","(-7875,3325)","0","pure_quanta","I162";
;
PART_NUMBER"CS-2203F902"
VALUE"2.2"
WATTAGE"1/10W"
TOLERANCE"1%"
PACK_TYPE"0603LF"
MATERIAL"CHIP"
$LOCATION"R572"
CDS_LIB"pure_quanta"
CDS_LOCATION"R572"
$SEC"1"
CDS_SEC"1";
"B"
$PN"2"3;
"A"
$PN"1"23;
%"Q_RES"
"1","(-7875,4200)","0","pure_quanta","I163";
;
PART_NUMBER"CS-2203F902"
TOLERANCE"1%"
MATERIAL"CHIP"
VALUE"2.2"
PACK_TYPE"0603LF"
WATTAGE"1/10W"
$LOCATION"R571"
CDS_LIB"pure_quanta"
CDS_LOCATION"R571"
$SEC"1"
CDS_SEC"1";
"B"
$PN"2"6;
"A"
$PN"1"23;
%"Q_CAP"
"1","(-7450,3100)","0","pure_quanta","I164";
;
PART_NUMBER"CH6101ME900"
VALUE"10UF"
VOLTAGE"6.3V"
TOLERANCE"20%"
MATERIAL"X6S"
PACK_TYPE"C0603"
$LOCATION"C209"
CDS_LIB"pure_quanta"
CDS_LOCATION"C209"
$SEC"1"
CDS_SEC"1";
"B"
$PN"2"17;
"A"
$PN"1"3;
%"Q_CAP"
"1","(-7075,3100)","0","pure_quanta","I165";
;
PART_NUMBER"CH4104K1B00"
PACK_TYPE"0402"
MATERIAL"X7R"
TOLERANCE"10%"
VOLTAGE"25V"
VALUE"0.1UF"
$LOCATION"C211"
CDS_LIB"pure_quanta"
BOM_COST"VR_SYSTEM "
CDS_LOCATION"C211"
$SEC"1"
CDS_SEC"1";
"B"
$PN"2"17;
"A"
$PN"1"3;
%"UNIVERSAL_POWER"
"1","(-7075,3450)","0","logical_power","I166";
;
HDL_POWER"P3V3_DB2000_VDDA"
CDS_LIB"logical_power";
"A"3;
%"Q_CAP"
"1","(-7450,3975)","0","pure_quanta","I167";
;
PART_NUMBER"CH6101ME900"
TOLERANCE"20%"
VALUE"10UF"
MATERIAL"X6S"
VOLTAGE"6.3V"
PACK_TYPE"C0603"
$LOCATION"C208"
CDS_LIB"pure_quanta"
CDS_LOCATION"C208"
$SEC"1"
CDS_SEC"1";
"B"
$PN"2"18;
"A"
$PN"1"6;
%"Q_CAP"
"1","(-7075,3975)","0","pure_quanta","I168";
;
PART_NUMBER"CH4104K1B00"
MATERIAL"X7R"
TOLERANCE"10%"
VALUE"0.1UF"
VOLTAGE"25V"
PACK_TYPE"0402"
$LOCATION"C210"
BOM_COST"VR_SYSTEM "
CDS_LIB"pure_quanta"
CDS_LOCATION"C210"
$SEC"1"
CDS_SEC"1";
"B"
$PN"2"18;
"A"
$PN"1"6;
%"UNIVERSAL_POWER"
"1","(-7075,4325)","0","logical_power","I169";
;
HDL_POWER"P3V3_DB2000_VDDR"
CDS_LIB"logical_power";
"A"6;
%"Q_INDUCTOR"
"1","(-9100,5250)","0","pure_quanta","I170";
;
PART_NUMBER"CX8SG331000"
VALUE"BLM18SG331TN1D/1.5A"
PACK_TYPE"SMLF"
MATERIAL"IND"
$LOCATION"L3"
CDS_LIB"pure_quanta"
NEEDS_NO_SIZE"TRUE"
CDS_LOCATION"L3"
$SEC"1"
CDS_SEC"1";
"1"
$PN"1"10;
"2"
$PN"2"7;
%"Q_CAP"
"1","(-8875,5000)","0","pure_quanta","I171";
;
PART_NUMBER"CH4104K1B00"
PACK_TYPE"0402"
MATERIAL"X7R"
TOLERANCE"10%"
VOLTAGE"25V"
VALUE"0.1UF"
$LOCATION"C204"
CDS_LIB"pure_quanta"
BOM_COST"VR_SYSTEM "
CDS_LOCATION"C204"
$SEC"1"
CDS_SEC"1";
"B"
$PN"2"15;
"A"
$PN"1"7;
%"Q_CAP"
"1","(-8475,5000)","0","pure_quanta","I172";
;
PART_NUMBER"CH4104K1B00"
VALUE"0.1UF"
PACK_TYPE"0402"
TOLERANCE"10%"
MATERIAL"X7R"
VOLTAGE"25V"
$LOCATION"C205"
CDS_LIB"pure_quanta"
BOM_COST"VR_SYSTEM "
CDS_LOCATION"C205"
$SEC"1"
CDS_SEC"1";
"B"
$PN"2"15;
"A"
$PN"1"7;
%"Q_CAP"
"1","(-8100,5000)","0","pure_quanta","I173";
;
PART_NUMBER"CH4104K1B00"
MATERIAL"X7R"
VOLTAGE"25V"
VALUE"0.1UF"
PACK_TYPE"0402"
TOLERANCE"10%"
$LOCATION"C206"
CDS_LIB"pure_quanta"
BOM_COST"VR_SYSTEM "
CDS_LOCATION"C206"
$SEC"1"
CDS_SEC"1";
"B"
$PN"2"15;
"A"
$PN"1"7;
%"Q_CAP"
"1","(-7725,5000)","0","pure_quanta","I174";
;
PART_NUMBER"CH4104K1B00"
VOLTAGE"25V"
VALUE"0.1UF"
MATERIAL"X7R"
TOLERANCE"10%"
PACK_TYPE"0402"
$LOCATION"C207"
BOM_COST"VR_SYSTEM "
CDS_LIB"pure_quanta"
CDS_LOCATION"C207"
$SEC"1"
CDS_SEC"1";
"B"
$PN"2"15;
"A"
$PN"1"7;
%"UNIVERSAL_POWER"
"1","(-7300,5500)","0","logical_power","I175";
;
HDL_POWER"P3V3_DB2000_VDD"
CDS_LIB"logical_power";
"A"7;
%"UNIVERSAL_POWER"
"1","(-9425,5525)","0","logical_power","I176";
;
HDL_POWER"P3V3"
CDS_LIB"logical_power";
"A"10;
%"Q_INDUCTOR"
"1","(-9100,4225)","0","pure_quanta","I177";
;
PART_NUMBER"CX8SG331000"
VALUE"BLM18SG331TN1D/1.5A"
PACK_TYPE"SMLF"
MATERIAL"IND"
$LOCATION"L4"
CDS_LIB"pure_quanta"
NEEDS_NO_SIZE"TRUE"
CDS_LOCATION"L4"
$SEC"1"
CDS_SEC"1";
"1"
$PN"1"2;
"2"
$PN"2"23;
%"Q_RES"
"2","(-9225,1475)","0","pure_quanta","I178";
;
PART_NUMBER"CS24702FB06"
MATERIAL"CHIP"
PACK_TYPE"0402LF"
WATTAGE"1/16W"
TOLERANCE"1%"
VALUE"4.7K"
$LOCATION"R568"
CDS_LIB"pure_quanta"
CDS_LOCATION"R568"
$SEC"1"
CDS_SEC"1";
"A"
$PN"1"72;
"B"
$PN"2"13;
%"Q_RES"
"2","(-9225,2050)","0","pure_quanta","I179";
;
PART_NUMBER"CS24702FB06"
MATERIAL"EMPTY"
TOLERANCE"1%"
PACK_TYPE"0402LF"
WATTAGE"1/16W"
VALUE"4.7K"
$LOCATION"R567"
CDS_LIB"pure_quanta"
CDS_LOCATION"R567"
$SEC"1"
CDS_SEC"1";
"A"
$PN"1"4;
"B"
$PN"2"72;
%"UNIVERSAL_POWER"
"1","(-9225,2375)","0","logical_power","I183";
;
HDL_POWER"P3V3"
CDS_LIB"logical_power";
"A"4;
%"Q_RES"
"2","(-8825,2050)","0","pure_quanta","I185";
;
PART_NUMBER"CS24702FB06"
MATERIAL"EMPTY"
PACK_TYPE"0402LF"
TOLERANCE"1%"
WATTAGE"1/16W"
VALUE"4.7K"
$LOCATION"R569"
CDS_LIB"pure_quanta"
CDS_LOCATION"R569"
$SEC"1"
CDS_SEC"1";
"A"
$PN"1"4;
"B"
$PN"2"20;
%"Q_RES"
"2","(-8825,1475)","0","pure_quanta","I187";
;
PART_NUMBER"CS24702FB06"
TOLERANCE"1%"
WATTAGE"1/16W"
MATERIAL"CHIP"
PACK_TYPE"0402LF"
VALUE"4.7K"
$LOCATION"R570"
CDS_LIB"pure_quanta"
CDS_LOCATION"R570"
$SEC"1"
CDS_SEC"1";
"A"
$PN"1"20;
"B"
$PN"2"19;
%"Q_RES"
"2","(-9225,625)","0","pure_quanta","I194";
;
PART_NUMBER"CS24702FB06"
TOLERANCE"1%"
MATERIAL"EMPTY"
PACK_TYPE"0402LF"
WATTAGE"1/16W"
VALUE"4.7K"
$LOCATION"R573"
CDS_LIB"pure_quanta"
CDS_LOCATION"R573"
$SEC"1"
CDS_SEC"1";
"A"
$PN"1"9;
"B"
$PN"2"27;
%"UNIVERSAL_POWER"
"1","(-9225,900)","0","logical_power","I195";
;
HDL_POWER"P3V3"
CDS_LIB"logical_power";
"A"9;
%"Q_RES"
"2","(-9225,50)","0","pure_quanta","I197";
;
PART_NUMBER"CS24702FB06"
TOLERANCE"1%"
VALUE"4.7K"
WATTAGE"1/16W"
MATERIAL"CHIP"
PACK_TYPE"0402LF"
$LOCATION"R574"
CDS_LIB"pure_quanta"
CDS_LOCATION"R574"
$SEC"1"
CDS_SEC"1";
"A"
$PN"1"27;
"B"
$PN"2"14;
%"Q_RES"
"1","(-5300,2550)","0","pure_quanta","I199";
;
PART_NUMBER"CS04992FB07"
TOLERANCE"1%"
MATERIAL"CHIP"
WATTAGE"1/16W"
VALUE"49.9"
PACK_TYPE"0402LF"
$LOCATION"R575"
CDS_LIB"pure_quanta"
CDS_LOCATION"R575"
$SEC"1"
CDS_SEC"1";
"B"
$PN"2"58;
"A"
$PN"1"25;
%"Q_RES"
"1","(-6225,2400)","0","pure_quanta","I304";
;
PART_NUMBER"CS22002FB07"
WATTAGE"1/16W"
VALUE"2K"
TOLERANCE"1%"
MATERIAL"CHIP"
PACK_TYPE"0402LF"
$LOCATION"R106"
CDS_LIB"pure_quanta"
CDS_LOCATION"R106"
$SEC"1"
CDS_SEC"1";
"B"
$PN"2"25;
"A"
$PN"1"16;
%"Q_CAP"
"1","(-7300,4975)","0","pure_quanta","I419";
;
PART_NUMBER"CH6101ME900"
TOLERANCE"20%"
VALUE"10UF"
VOLTAGE"6.3V"
MATERIAL"X6S"
PACK_TYPE"C0603"
$LOCATION"C1409"
CDS_LIB"pure_quanta"
CDS_LOCATION"C1409"
$SEC"1"
CDS_SEC"1";
"B"
$PN"2"15;
"A"
$PN"1"7;
%"UNIVERSAL_GND"
"1","(-7075,3650)","0","logical_power","I432";
;
HDL_POWER"GND"
CDS_LIB"logical_power";
"A"18;
%"UNIVERSAL_GND"
"1","(-7075,2775)","0","logical_power","I433";
;
HDL_POWER"GND"
CDS_LIB"logical_power";
"A"17;
%"UNIVERSAL_GND"
"1","(-6575,2325)","0","logical_power","I434";
;
CDS_LIB"logical_power"
HDL_POWER"GND";
"A"16;
%"UNIVERSAL_GND"
"1","(-7300,4700)","0","logical_power","I435";
;
HDL_POWER"GND"
CDS_LIB"logical_power";
"A"15;
%"UNIVERSAL_GND"
"1","(-9225,-200)","0","logical_power","I436";
;
HDL_POWER"GND"
CDS_LIB"logical_power";
"A"14;
%"UNIVERSAL_GND"
"1","(-9225,1225)","0","logical_power","I437";
;
HDL_POWER"GND"
CDS_LIB"logical_power";
"A"13;
%"UNIVERSAL_GND"
"1","(-8825,1225)","0","logical_power","I438";
;
HDL_POWER"GND"
CDS_LIB"logical_power";
"A"19;
%"UNIVERSAL_GND"
"1","(-2175,375)","0","logical_power","I439";
;
HDL_POWER"GND"
CDS_LIB"logical_power";
"A"12;
%"Q_RES"
"1","(-5300,2100)","0","pure_quanta","I487";
;
PART_NUMBER"CS00002JB13"
VALUE"0"
TOLERANCE"5%"
MATERIAL"CHIP"
$LOCATION"R4534"
CDS_LIB"pure_quanta"
PACK_TYPE"0402LF"
WATTAGE"1/16W"
CDS_LOCATION"R4534"
$SEC"1"
CDS_SEC"1";
"B"
$PN"2"71;
"A"
$PN"1"22;
%"Q_RES"
"1","(-5300,2050)","0","pure_quanta","I534";
;
PART_NUMBER"CS00002JB13"
VALUE"0"
MATERIAL"CHIP"
TOLERANCE"5%"
LOCATION"R1543"
CDS_LIB"pure_quanta"
WATTAGE"1/16W"
PACK_TYPE"0402LF"
$SEC"1"
CDS_SEC"1";
"B"
$PN"2"90;
"A"
$PN"1"21;
%"Q_RES"
"1","(-5300,2000)","0","pure_quanta","I535";
;
PART_NUMBER"CS00002JB13"
VALUE"0"
TOLERANCE"5%"
MATERIAL"CHIP"
LOCATION"R2562"
CDS_LIB"pure_quanta"
PACK_TYPE"0402LF"
WATTAGE"1/16W"
$SEC"1"
CDS_SEC"1";
"B"
$PN"2"69;
"A"
$PN"1"21;
%"Q_RES"
"1","(-5300,1950)","0","pure_quanta","I536";
;
PART_NUMBER"CS00002JB13"
VALUE"0"
TOLERANCE"5%"
MATERIAL"CHIP"
LOCATION"R3636"
CDS_LIB"pure_quanta"
PACK_TYPE"0402LF"
WATTAGE"1/16W"
$SEC"1"
CDS_SEC"1";
"B"
$PN"2"75;
"A"
$PN"1"21;
%"Q_RES"
"1","(-5300,1900)","0","pure_quanta","I537";
;
PART_NUMBER"CS00002JB13"
VALUE"0"
MATERIAL"CHIP"
TOLERANCE"5%"
LOCATION"R3637"
CDS_LIB"pure_quanta"
PACK_TYPE"0402LF"
WATTAGE"1/16W"
$SEC"1"
CDS_SEC"1";
"B"
$PN"2"70;
"A"
$PN"1"21;
%"Q_RES"
"2","(-7450,2425)","0","pure_quanta","I539";
;
PART_NUMBER"CS31002FB08"
TOLERANCE"1%"
WATTAGE"1/16W"
PACK_TYPE"0402LF"
VALUE"10K"
MATERIAL"CHIP"
$LOCATION"R4516"
CDS_LIB"pure_quanta"
CDS_LOCATION"R4516"
$SEC"1"
CDS_SEC"1";
"A"
$PN"1"1;
"B"
$PN"2"22;
%"Q_RES"
"2","(-7125,2425)","0","pure_quanta","I540";
;
PART_NUMBER"CS31002FB08"
PACK_TYPE"0402LF"
TOLERANCE"1%"
WATTAGE"1/16W"
MATERIAL"CHIP"
VALUE"10K"
$LOCATION"R4517"
CDS_LIB"pure_quanta"
CDS_LOCATION"R4517"
$SEC"1"
CDS_SEC"1";
"A"
$PN"1"1;
"B"
$PN"2"21;
%"UNIVERSAL_POWER"
"1","(-7450,2775)","0","logical_power","I541";
;
HDL_POWER"P3V3"
CDS_LIB"logical_power";
"A"1;
END.
